# T6G (Grand Teton) — schematic parts with pin connectivity, parts 8081–8081 of 8303; source: Cadence DE-HDL packaged netlist (pstxprt.dat, pstxnet.dat, pstchip.dat)

U25  GENOA_SP5  SOCKET6096_13568-001 IO  pkg SOCKET6096_93-4X120-45XA  page 10  (pins 1345-1680 of 6096)
  AV67  MFA0_CS_L0  OUT  = M_F_CPU0_SA_CS_N<0>
  AV68  VSS_AV68  POWER  = GND
  AV69  MEA1_CS_L1  OUT  = NC
  AV70  MEA0_CS_L0  OUT  = M_E_CPU0_SA_CS_N<0>
  AV71  VDDIO_AV71  POWER  = PVDDIO_P0
  AV72  MAA1_CS_L1  OUT  = NC
  AV73  VSS_AV73  POWER  = GND
  AV74  MAA0_CS_L0  OUT  = M_A_CPU0_SA_CS_N<0>
  AW1  VSS_AW1  POWER  = GND
  AW2  MGA_CA0  OUT  = M_G_CPU0_SA_CA<0>
  AW3  MGA1_CS_L1  OUT  = NC
  AW4  VSS_AW4  POWER  = GND
  AW5  MKA_CA0  OUT  = M_K_CPU0_SA_CA<0>
  AW6  VSS_AW6  POWER  = GND
  AW7  MKA1_CS_L1  OUT  = NC
  AW8  VSS_AW8  POWER  = GND
  AW9  MLA_CA0  OUT  = M_L_CPU0_SA_CA<0>
  AW10  MLA1_CS_L1  OUT  = NC
  AW11  VSS_AW11  POWER  = GND
  AW12  MHA_CA0  OUT  = M_H_CPU0_SA_CA<0>
  AW13  VSS_AW13  POWER  = GND
  AW14  MHA1_CS_L1  OUT  = NC
  AW15  VSS_AW15  POWER  = GND
  AW16  MJA_CA0  OUT  = M_J_CPU0_SA_CA<0>
  AW17  MJA1_CS_L1  OUT  = NC
  AW18  VSS_AW18  POWER  = GND
  AW19  MIA_CA0  OUT  = M_I_CPU0_SA_CA<0>
  AW20  VSS_AW20  POWER  = GND
  AW21  MIA1_CS_L1  OUT  = NC
  AW22  VSS_AW22  POWER  = GND
  AW23  VDDCR_SOC_AW23  POWER  = PVDDCR_SOC_P0
  AW24  VSS_AW24  POWER  = GND
  AW25  VDDCR_SOC_AW25  POWER  = PVDDCR_SOC_P0
  AW26  VSS_AW26  POWER  = GND
  AW27  VDDCR_SOC_AW27  POWER  = PVDDCR_SOC_P0
  AW28  VSS_AW28  POWER  = GND
  AW48  VDDCR_SOC_AW48  POWER  = PVDDCR_SOC_P0
  AW49  VSS_AW49  POWER  = GND
  AW50  VDD_18_S5_AW50  POWER  = PVDD18_S5_P0
  AW51  VSS_AW51  POWER  = GND
  AW52  VDD_18_S5_AW52  POWER  = PVDD18_S5_P0
  AW53  VSS_AW53  POWER  = GND
  AW54  VDD_18_S5_AW54  POWER  = PVDD18_S5_P0
  AW55  MCA0_CS_L1  OUT  = M_C_CPU0_SA_CS_N<1>
  AW56  VSS_AW56  POWER  = GND
  AW57  MCA_CA0  OUT  = M_C_CPU0_SA_CA<0>
  AW58  VSS_AW58  POWER  = GND
  AW59  MDA0_CS_L1  OUT  = M_D_CPU0_SA_CS_N<1>
  AW60  MDA_CA0  OUT  = M_D_CPU0_SA_CA<0>
  AW61  VSS_AW61  POWER  = GND
  AW62  MBA0_CS_L1  OUT  = M_B_CPU0_SA_CS_N<1>
  AW63  VSS_AW63  POWER  = GND
  AW64  MBA_CA0  OUT  = M_B_CPU0_SA_CA<0>
  AW65  VSS_AW65  POWER  = GND
  AW66  MFA0_CS_L1  OUT  = M_F_CPU0_SA_CS_N<1>
  AW67  MFA_CA0  OUT  = M_F_CPU0_SA_CA<0>
  AW68  VSS_AW68  POWER  = GND
  AW69  MEA0_CS_L1  OUT  = M_E_CPU0_SA_CS_N<1>
  AW70  VSS_AW70  POWER  = GND
  AW71  MEA_CA0  OUT  = M_E_CPU0_SA_CA<0>
  AW72  VSS_AW72  POWER  = GND
  AW73  MAA0_CS_L1  OUT  = M_A_CPU0_SA_CS_N<1>
  AW74  MAA_CA0  OUT  = M_A_CPU0_SA_CA<0>
  AW75  VSS_AW75  POWER  = GND
  AY2  MGA_CA1  OUT  = M_G_CPU0_SA_CA<1>
  AY3  VSS_AY3  POWER  = GND
  AY4  MGA_CA2  OUT  = M_G_CPU0_SA_CA<2>
  AY5  VSS_AY5  POWER  = GND
  AY6  MKA_CA1  OUT  = M_K_CPU0_SA_CA<1>
  AY7  MKA_CA2  OUT  = M_K_CPU0_SA_CA<2>
  AY8  VSS_AY8  POWER  = GND
  AY9  MLA_CA1  OUT  = M_L_CPU0_SA_CA<1>
  AY10  VSS_AY10  POWER  = GND
  AY11  MLA_CA2  OUT  = M_L_CPU0_SA_CA<2>
  AY12  VSS_AY12  POWER  = GND
  AY13  MHA_CA1  OUT  = M_H_CPU0_SA_CA<1>
  AY14  MHA_CA2  OUT  = M_H_CPU0_SA_CA<2>
  AY15  VSS_AY15  POWER  = GND
  AY16  MJA_CA1  OUT  = M_J_CPU0_SA_CA<1>
  AY17  VSS_AY17  POWER  = GND
  AY18  MJA_CA2  OUT  = M_J_CPU0_SA_CA<2>
  AY19  VSS_AY19  POWER  = GND
  AY20  MIA_CA1  OUT  = M_I_CPU0_SA_CA<1>
  AY21  MIA_CA2  OUT  = M_I_CPU0_SA_CA<2>
  AY22  VDDCR_SOC_AY22  POWER  = PVDDCR_SOC_P0
  AY23  VSS_AY23  POWER  = GND
  AY24  VDDCR_SOC_AY24  POWER  = PVDDCR_SOC_P0
  AY25  VSS_AY25  POWER  = GND
  AY26  VDDCR_SOC_AY26  POWER  = PVDDCR_SOC_P0
  AY27  VSS_AY27  POWER  = GND
  AY28  VDDCR_SOC_AY28  POWER  = PVDDCR_SOC_P0
  AY48  VSS_AY48  POWER  = GND
  AY49  VDDCR_SOC_AY49  POWER  = PVDDCR_SOC_P0
  AY50  VSS_AY50  POWER  = GND
  AY51  VDD_18_S5_AY51  POWER  = PVDD18_S5_P0
  AY52  VSS_AY52  POWER  = GND
  AY53  VDD_18_S5_AY53  POWER  = PVDD18_S5_P0
  AY54  VSS_AY54  POWER  = GND
  AY55  MCA_CA2  OUT  = M_C_CPU0_SA_CA<2>
  AY56  MCA_CA1  OUT  = M_C_CPU0_SA_CA<1>
  AY57  VSS_AY57  POWER  = GND
  AY58  MDA_CA2  OUT  = M_D_CPU0_SA_CA<2>
  AY59  VSS_AY59  POWER  = GND
  AY60  MDA_CA1  OUT  = M_D_CPU0_SA_CA<1>
  AY61  VSS_AY61  POWER  = GND
  AY62  MBA_CA2  OUT  = M_B_CPU0_SA_CA<2>
  AY63  MBA_CA1  OUT  = M_B_CPU0_SA_CA<1>
  AY64  VSS_AY64  POWER  = GND
  AY65  MFA_CA2  OUT  = M_F_CPU0_SA_CA<2>
  AY66  VSS_AY66  POWER  = GND
  AY67  MFA_CA1  OUT  = M_F_CPU0_SA_CA<1>
  AY68  VSS_AY68  POWER  = GND
  AY69  MEA_CA2  OUT  = M_E_CPU0_SA_CA<2>
  AY70  MEA_CA1  OUT  = M_E_CPU0_SA_CA<1>
  AY71  VSS_AY71  POWER  = GND
  AY72  MAA_CA2  OUT  = M_A_CPU0_SA_CA<2>
  AY73  VSS_AY73  POWER  = GND
  AY74  MAA_CA1  OUT  = M_A_CPU0_SA_CA<1>
  B3  VDDCR_SOC_SENSE  POWER  = VSENSE_PVDDCR_SOC_P0_DP
  B4  \i3c3_sda||i2c3_sda||spd3_sda||agpio152\  BI  = SMB_CPU0_3_R_SDA
  B5  VDDCR_SOC_B5  POWER  = PVDDCR_SOC_P0
  B6  GPP_CLK02P  OUT  = CLK_100M_CPU0_CLK02_R_DP
  B7  VSS_B7  POWER  = GND
  B8  VSS_B8  POWER  = GND
  B9  GPP_CLK05P  OUT  = CLK_100M_CPU0_CLK05_R_DP
  B10  VSS_B10  POWER  = GND
  B11  VSS_B11  POWER  = GND
  B12  GPP_CLK04P  OUT  = CLK_100M_CPU0_CLK04_R_DP
  B13  VSS_B13  POWER  = GND
  B14  \sec_scl||agpio262\  BI  = SMB_CPU0_SEC_SCL
  B15  \sgpio_load||agpio261\  BI  = NC
  B16  \agpio259||sgpio3_clk\  BI  = NC
  B17  TCK  IN  = JTAG_CPU0_TCK
  B18  VSS_B18  POWER  = GND
  B19  VDDCR_CPU0_B19  POWER  = PVDDCR_CPU0_P0
  B20  VDDCR_CPU0_B20  POWER  = PVDDCR_CPU0_P0
  B21  SVT0  IN  = SVID_PVDDCR_CPU0_P0_SVTO
  B22  VDDCR_CPU0_B22  POWER  = PVDDCR_CPU0_P0
  B23  VDDCR_CPU0_B23  POWER  = PVDDCR_CPU0_P0
  B24  VSS_B24  POWER  = GND
  B25  VDDCR_CPU0_B25  POWER  = PVDDCR_CPU0_P0
  B26  VDDCR_CPU0_B26  POWER  = PVDDCR_CPU0_P0
  B27  VSS_B27  POWER  = GND
  B28  VDDCR_CPU0_B28  POWER  = PVDDCR_CPU0_P0
  B29  VDDCR_CPU0_B29  POWER  = PVDDCR_CPU0_P0
  B30  VSS_B30  POWER  = GND
  B31  VDDCR_CPU0_B31  POWER  = PVDDCR_CPU0_P0
  B32  VDDCR_CPU0_B32  POWER  = PVDDCR_CPU0_P0
  B33  VSS_B33  POWER  = GND
  B34  VDDCR_CPU0_B34  POWER  = PVDDCR_CPU0_P0
  B35  VDDCR_CPU0_B35  POWER  = PVDDCR_CPU0_P0
  B36  TEST6_X3D6  OUT  = NC
  B37  VSS_B37  POWER  = GND
  B39  VSS_B39  POWER  = GND
  B40  RSVD_B40  TRI  = NC
  B41  VDDCR_CPU0_B41  POWER  = PVDDCR_CPU0_P0
  B42  VDDCR_CPU0_B42  POWER  = PVDDCR_CPU0_P0
  B43  VSS_B43  POWER  = GND
  B44  VDDCR_CPU0_B44  POWER  = PVDDCR_CPU0_P0
  B45  VDDCR_CPU0_B45  POWER  = PVDDCR_CPU0_P0
  B46  VSS_B46  POWER  = GND
  B47  VDDCR_CPU0_B47  POWER  = PVDDCR_CPU0_P0
  B48  VDDCR_CPU0_B48  POWER  = PVDDCR_CPU0_P0
  B49  VSS_B49  POWER  = GND
  B50  VDDCR_CPU0_B50  POWER  = PVDDCR_CPU0_P0
  B51  VDDCR_CPU0_B51  POWER  = PVDDCR_CPU0_P0
  B52  VSS_B52  POWER  = GND
  B53  VDDCR_CPU0_B53  POWER  = PVDDCR_CPU0_P0
  B54  VDDCR_CPU0_B54  POWER  = PVDDCR_CPU0_P0
  B55  VSS_B55  POWER  = GND
  B56  VDDCR_CPU0_B56  POWER  = PVDDCR_CPU0_P0
  B57  VDDCR_CPU0_B57  POWER  = PVDDCR_CPU0_P0
  B58  TEST47_IOD0  TRI  = TP_CPU0_TEST47_IOD0
  B59  VSS_B59  POWER  = GND
  B60  TEST47_CCD0  TRI  = TP_CPU0_TEST47_CCD0
  B61  TEST50_IOD  TRI  = TP_CPU0_TEST50_IOD
  B62  VSS_B62  POWER  = GND
  B63  FORCE_SELFREFRESH  IN  = CPU0_FORCE_SELFREFRESH
  B64  NV_SAVE_L  OUT  = CPU0_NV_SAVE_N
  B65  VSS_B65  POWER  = GND
  B66  CPU_PRESENT_L  OUT  = PRSNT_CPU0_N
  B67  RESET_L  BI  = RST_CPU0_RESETL_N
  B68  VSS_B68  POWER  = GND
  B69  CORETYPE1  OUT  = CPU0_CORETYPE1
  B70  VSS_B70  POWER  = GND
  B71  \i3c0_sda||i2c0_sda||spd0_sda||smbus0_sda||agpio146\  BI  = I3C_0_SPD_DDRAF_CPU0_R_SDA
  B72  \i3c2_sda||i2c2_sda||spd2_sda||agpio150\  BI  = SMB_CPU0_2_R_SDA
  B73  VSS_SENSE_D  POWER  = VSENSE_PVDD18_S5_P0_DN
  BA1  VSS_BA1  POWER  = GND
  BA2  MGA_CA4  OUT  = M_G_CPU0_SA_CA<4>
  BA3  MGA_CA3  OUT  = M_G_CPU0_SA_CA<3>
  BA4  VDDCR_SOC_BA4  POWER  = PVDDCR_SOC_P0
  BA5  MKA_CA4  OUT  = M_K_CPU0_SA_CA<4>
  BA6  VSS_BA6  POWER  = GND
  BA7  MKA_CA3  OUT  = M_K_CPU0_SA_CA<3>
  BA8  VSS_BA8  POWER  = GND
  BA9  MLA_CA4  OUT  = M_L_CPU0_SA_CA<4>
  BA10  MLA_CA3  OUT  = M_L_CPU0_SA_CA<3>
  BA11  VDDCR_SOC_BA11  POWER  = PVDDCR_SOC_P0
  BA12  MHA_CA4  OUT  = M_H_CPU0_SA_CA<4>
  BA13  VSS_BA13  POWER  = GND
  BA14  MHA_CA3  OUT  = M_H_CPU0_SA_CA<3>
  BA15  VSS_BA15  POWER  = GND
  BA16  MJA_CA4  OUT  = M_J_CPU0_SA_CA<4>
  BA17  MJA_CA3  OUT  = M_J_CPU0_SA_CA<3>
  BA18  VDDCR_SOC_BA18  POWER  = PVDDCR_SOC_P0
  BA19  MIA_CA4  OUT  = M_I_CPU0_SA_CA<4>
  BA20  VSS_BA20  POWER  = GND
  BA21  MIA_CA3  OUT  = M_I_CPU0_SA_CA<3>
  BA22  VSS_BA22  POWER  = GND
  BA23  VDDCR_SOC_BA23  POWER  = PVDDCR_SOC_P0
  BA24  VSS_BA24  POWER  = GND
  BA25  VDDCR_SOC_BA25  POWER  = PVDDCR_SOC_P0
  BA26  VSS_BA26  POWER  = GND
  BA27  VDDCR_SOC_BA27  POWER  = PVDDCR_SOC_P0
  BA28  VSS_BA28  POWER  = GND
  BA48  VDDCR_SOC_BA48  POWER  = PVDDCR_SOC_P0
  BA49  VSS_BA49  POWER  = GND
  BA50  VDD_18_S5_BA50  POWER  = PVDD18_S5_P0
  BA51  VSS_BA51  POWER  = GND
  BA52  VDD_18_S5_BA52  POWER  = PVDD18_S5_P0
  BA53  VSS_BA53  POWER  = GND
  BA54  VDD_18_S5_BA54  POWER  = PVDD18_S5_P0
  BA55  MCA_CA3  OUT  = M_C_CPU0_SA_CA<3>
  BA56  VSS_BA56  POWER  = GND
  BA57  MCA_CA4  OUT  = M_C_CPU0_SA_CA<4>
  BA58  VDDIO_BA58  POWER  = PVDDIO_P0
  BA59  MDA_CA3  OUT  = M_D_CPU0_SA_CA<3>
  BA60  MDA_CA4  OUT  = M_D_CPU0_SA_CA<4>
  BA61  VSS_BA61  POWER  = GND
  BA62  MBA_CA3  OUT  = M_B_CPU0_SA_CA<3>
  BA63  VSS_BA63  POWER  = GND
  BA64  MBA_CA4  OUT  = M_B_CPU0_SA_CA<4>
  BA65  VDDIO_BA65  POWER  = PVDDIO_P0
  BA66  MFA_CA3  OUT  = M_F_CPU0_SA_CA<3>
  BA67  MFA_CA4  OUT  = M_F_CPU0_SA_CA<4>
  BA68  VSS_BA68  POWER  = GND
  BA69  MEA_CA3  OUT  = M_E_CPU0_SA_CA<3>
  BA70  VSS_BA70  POWER  = GND
  BA71  MEA_CA4  OUT  = M_E_CPU0_SA_CA<4>
  BA72  VDDIO_BA72  POWER  = PVDDIO_P0
  BA73  MAA_CA3  OUT  = M_A_CPU0_SA_CA<3>
  BA74  MAA_CA4  OUT  = M_A_CPU0_SA_CA<4>
  BA75  VSS_BA75  POWER  = GND
  BB2  MGA_CA5  OUT  = M_G_CPU0_SA_CA<5>
  BB3  VSS_BB3  POWER  = GND
  BB4  MGA_CA6  OUT  = M_G_CPU0_SA_CA<6>
  BB5  VSS_BB5  POWER  = GND
  BB6  MKA_CA5  OUT  = M_K_CPU0_SA_CA<5>
  BB7  MKA_CA6  OUT  = M_K_CPU0_SA_CA<6>
  BB8  VSS_BB8  POWER  = GND
  BB9  MLA_CA5  OUT  = M_L_CPU0_SA_CA<5>
  BB10  VSS_BB10  POWER  = GND
  BB11  MLA_CA6  OUT  = M_L_CPU0_SA_CA<6>
  BB12  VSS_BB12  POWER  = GND
  BB13  MHA_CA5  OUT  = M_H_CPU0_SA_CA<5>
  BB14  MHA_CA6  OUT  = M_H_CPU0_SA_CA<6>
  BB15  VSS_BB15  POWER  = GND
  BB16  MJA_CA5  OUT  = M_J_CPU0_SA_CA<5>
  BB17  VSS_BB17  POWER  = GND
  BB18  MJA_CA6  OUT  = M_J_CPU0_SA_CA<6>
  BB19  VSS_BB19  POWER  = GND
  BB20  MIA_CA5  OUT  = M_I_CPU0_SA_CA<5>
  BB21  MIA_CA6  OUT  = M_I_CPU0_SA_CA<6>
  BB22  VDDCR_SOC_BB22  POWER  = PVDDCR_SOC_P0
  BB23  VSS_BB23  POWER  = GND
  BB24  VDDCR_SOC_BB24  POWER  = PVDDCR_SOC_P0
  BB25  VSS_BB25  POWER  = GND
  BB26  VDDCR_SOC_BB26  POWER  = PVDDCR_SOC_P0
  BB27  VSS_BB27  POWER  = GND
  BB28  VDDCR_SOC_BB28  POWER  = PVDDCR_SOC_P0
  BB48  VSS_BB48  POWER  = GND
  BB49  VDDCR_SOC_BB49  POWER  = PVDDCR_SOC_P0
  BB50  VSS_BB50  POWER  = GND
  BB51  VDD_18_S5_BB51  POWER  = PVDD18_S5_P0
  BB52  VSS_BB52  POWER  = GND
  BB53  VDD_18_S5_BB53  POWER  = PVDD18_S5_P0
  BB54  VSS_BB54  POWER  = GND
  BB55  MCA_CA6  OUT  = M_C_CPU0_SA_CA<6>
  BB56  MCA_CA5  OUT  = M_C_CPU0_SA_CA<5>
  BB57  VSS_BB57  POWER  = GND
  BB58  MDA_CA6  OUT  = M_D_CPU0_SA_CA<6>
  BB59  VSS_BB59  POWER  = GND
  BB60  MDA_CA5  OUT  = M_D_CPU0_SA_CA<5>
  BB61  VSS_BB61  POWER  = GND
  BB62  MBA_CA6  OUT  = M_B_CPU0_SA_CA<6>
  BB63  MBA_CA5  OUT  = M_B_CPU0_SA_CA<5>
  BB64  VSS_BB64  POWER  = GND
  BB65  MFA_CA6  OUT  = M_F_CPU0_SA_CA<6>
  BB66  VSS_BB66  POWER  = GND
  BB67  MFA_CA5  OUT  = M_F_CPU0_SA_CA<5>
  BB68  VSS_BB68  POWER  = GND
  BB69  MEA_CA6  OUT  = M_E_CPU0_SA_CA<6>
  BB70  MEA_CA5  OUT  = M_E_CPU0_SA_CA<5>
  BB71  VSS_BB71  POWER  = GND
  BB72  MAA_CA6  OUT  = M_A_CPU0_SA_CA<6>
  BB73  VSS_BB73  POWER  = GND
  BB74  MAA_CA5  OUT  = M_A_CPU0_SA_CA<5>
  BC1  VSS_BC1  POWER  = GND
  BC2  MG0_CLK_H  OUT  = M_G_CPU0_CLK_DP<0>
  BC3  MGA_PAR  OUT  = M_G_CPU0_SA_PAR
  BC4  VSS_BC4  POWER  = GND
  BC5  MK0_CLK_H  OUT  = M_K_CPU0_CLK_DP<0>
  BC6  VSS_BC6  POWER  = GND
  BC7  MKA_PAR  OUT  = M_K_CPU0_SA_PAR
  BC8  VSS_BC8  POWER  = GND
  BC9  ML0_CLK_H  OUT  = M_L_CPU0_CLK_DP<0>
  BC10  MLA_PAR  OUT  = M_L_CPU0_SA_PAR
  BC11  VSS_BC11  POWER  = GND
  BC12  MH0_CLK_H  OUT  = M_H_CPU0_CLK_DP<0>
  BC13  VSS_BC13  POWER  = GND
  BC14  MHA_PAR  OUT  = M_H_CPU0_SA_PAR
  BC15  VSS_BC15  POWER  = GND
  BC16  MJ0_CLK_H  OUT  = M_J_CPU0_CLK_DP<0>
  BC17  MJA_PAR  OUT  = M_J_CPU0_SA_PAR
  BC18  VSS_BC18  POWER  = GND
  BC19  MI0_CLK_H  OUT  = M_I_CPU0_CLK_DP<0>
  BC20  VSS_BC20  POWER  = GND
  BC21  MIA_PAR  OUT  = M_I_CPU0_SA_PAR
  BC22  VSS_BC22  POWER  = GND
  BC23  VDDCR_SOC_BC23  POWER  = PVDDCR_SOC_P0
  BC24  VSS_BC24  POWER  = GND
  BC25  VDDCR_SOC_BC25  POWER  = PVDDCR_SOC_P0
  BC26  VSS_BC26  POWER  = GND
  BC27  VDDCR_SOC_BC27  POWER  = PVDDCR_SOC_P0
  BC28  VSS_BC28  POWER  = GND
  BC48  VDDCR_SOC_BC48  POWER  = PVDDCR_SOC_P0
  BC49  VSS_BC49  POWER  = GND
  BC50  VSS_BC50  POWER  = GND
  BC51  VSS_BC51  POWER  = GND
  BC52  VDD_18_S5_BC52  POWER  = PVDD18_S5_P0
  BC53  VSS_BC53  POWER  = GND
  BC54  VDD_18_S5_BC54  POWER  = PVDD18_S5_P0
  BC55  MCA_PAR  OUT  = M_C_CPU0_SA_PAR
  BC56  VSS_BC56  POWER  = GND
  BC57  MC0_CLK_H  OUT  = M_C_CPU0_CLK_DP<0>
